# S9S_MB_2U (Grand Teton) — schematic netlist excerpt (pin names and nets, part order shuffled) for the footprints in the layout excerpt that follows; sources: Cadence DE-HDL packaged netlist, KiCad conversion of 03242023_DA0F0TMBIJ0_F0T_Motherboard_J_brd_V01_OCP.brd

R767  Q_RES  1K 1% CHIP  pkg 0402LF  page 131 : A = P3V3_AUX ; B = JTAG_RST_DBP_RST_CO_N
D95  Q_LED  IC  pkg SMLF  page 252 : A = LED_FM_PCH_SLP_S3_N ; C = LED_FM_PCH_SLP_S3_N_D

(kicad_pcb
	(version 20260206)
	(generator "pcbnew")
	(generator_version "10.0")
	(general
		(thickness 1.6)
		(legacy_teardrops no)
	)
	(paper "A4")
	(title_block
		(title "03242023_DA0F0TMBIJ0_F0T_Motherboard_J_brd_V01_OCP.brd")
		(comment 1 "Grand Teton / footprints 1100-1101 of 6105")
	)
	(layers
		(0 "F.Cu" signal "TOP")
		(4 "In1.Cu" signal "GND")
		(6 "In2.Cu" signal "IN1")
		(8 "In3.Cu" signal "GND1")
		(10 "In4.Cu" signal "IN2")
		(12 "In5.Cu" signal "GND2")
		(14 "In6.Cu" signal "IN3")
		(16 "In7.Cu" signal "GND3")
		(18 "In8.Cu" signal "VCC")
		(20 "In9.Cu" signal "VCC1")
		(22 "In10.Cu" signal "GND4")
		(24 "In11.Cu" signal "IN4")
		(26 "In12.Cu" signal "GND5")
		(28 "In13.Cu" signal "IN5")
		(30 "In14.Cu" signal "GND6")
		(32 "In15.Cu" signal "IN6")
		(34 "In16.Cu" signal "GND7")
		(2 "B.Cu" signal "BOTTOM")
		(9 "F.Adhes" user "F.Adhesive")
		(11 "B.Adhes" user "B.Adhesive")
		(13 "F.Paste" user "Package Geometry/Pastemask Top")
		(15 "B.Paste" user "Package Geometry/Pastemask Bottom")
		(5 "F.SilkS" user "Ref Des/Silkscreen Top")
		(7 "B.SilkS" user "Ref Des/Silkscreen Bottom")
		(1 "F.Mask" user "Board Geometry/Soldermask Top")
		(3 "B.Mask" user "Board Geometry/Soldermask Bottom")
		(17 "Dwgs.User" user "User.Drawings")
		(19 "Cmts.User" user "User.Comments")
		(21 "Eco1.User" user "User.Eco1")
		(23 "Eco2.User" user "User.Eco2")
		(25 "Edge.Cuts" user "Board Geometry/Outline")
		(27 "Margin" user)
		(31 "F.CrtYd" user "Package Geometry/Place Bound Top")
		(29 "B.CrtYd" user "Package Geometry/Place Bound Bottom")
		(35 "F.Fab" user "Ref Des/Assembly Top")
		(33 "B.Fab" user "Ref Des/Assembly Bottom")
	)
	(footprint ""
		(layer "F.Cu")
		(at 403.946106 -65.085976 180)
		(property "Reference" "R767"
			(at 0 0 180)
			(layer "F.SilkS")
			(hide yes)
			(effects
				(font
					(size 1.27 1.27)
				)
			)
		)
		(property "Value" ""
			(at 0 0 180)
			(layer "F.Fab")
			(effects
				(font
					(size 1.27 1.27)
				)
			)
		)
		(duplicate_pad_numbers_are_jumpers no)
		(fp_line
			(start 0.7874 0.4064)
			(end -0.7874 0.4064)
			(stroke
				(width 0.1524)
				(type default)
			)
			(layer "F.SilkS")
		)
		(fp_line
			(start 0.7874 -0.4064)
			(end 0.7874 0.4064)
			(stroke
				(width 0.1524)
				(type default)
			)
			(layer "F.SilkS")
		)
		(fp_line
			(start -0.7874 0.4064)
			(end -0.7874 -0.4064)
			(stroke
				(width 0.1524)
				(type default)
			)
			(layer "F.SilkS")
		)
		(fp_line
			(start -0.7874 -0.4064)
			(end 0.7874 -0.4064)
			(stroke
				(width 0.1524)
				(type default)
			)
			(layer "F.SilkS")
		)
		(fp_line
			(start 0.67945 0.3048)
			(end 0.120396 0.3048)
			(stroke
				(width 0.1)
				(type default)
			)
			(layer "F.Fab")
		)
		(fp_line
			(start 0.67945 -0.3048)
			(end 0.67945 0.3048)
			(stroke
				(width 0.1)
				(type default)
			)
			(layer "F.Fab")
		)
		(fp_line
			(start 0.12065 -0.2794)
			(end 0.12065 -0.3048)
			(stroke
				(width 0.1)
				(type default)
			)
			(layer "F.Fab")
		)
		(fp_line
			(start 0.12065 -0.3048)
			(end 0.67945 -0.3048)
			(stroke
				(width 0.1)
				(type default)
			)
			(layer "F.Fab")
		)
		(fp_line
			(start 0.120396 0.3048)
			(end 0.120396 0.2794)
			(stroke
				(width 0.1)
				(type default)
			)
			(layer "F.Fab")
		)
		(fp_line
			(start 0.120396 0.2794)
			(end -0.12065 0.2794)
			(stroke
				(width 0.1)
				(type default)
			)
			(layer "F.Fab")
		)
		(fp_line
			(start -0.12065 0.3048)
			(end -0.67945 0.3048)
			(stroke
				(width 0.1)
				(type default)
			)
			(layer "F.Fab")
		)
		(fp_line
			(start -0.12065 0.2794)
			(end -0.12065 0.3048)
			(stroke
				(width 0.1)
				(type default)
			)
			(layer "F.Fab")
		)
		(fp_line
			(start -0.12065 -0.2794)
			(end 0.12065 -0.2794)
			(stroke
				(width 0.1)
				(type default)
			)
			(layer "F.Fab")
		)
		(fp_line
			(start -0.12065 -0.305054)
			(end -0.12065 -0.2794)
			(stroke
				(width 0.1)
				(type default)
			)
			(layer "F.Fab")
		)
		(fp_line
			(start -0.67945 0.3048)
			(end -0.67945 -0.305054)
			(stroke
				(width 0.1)
				(type default)
			)
			(layer "F.Fab")
		)
		(fp_line
			(start -0.67945 -0.305054)
			(end -0.12065 -0.305054)
			(stroke
				(width 0.1)
				(type default)
			)
			(layer "F.Fab")
		)
		(pad "1" smd circle
			(at -0.40005 0 180)
			(size 0 0)
			(layers "F.Cu" "F.Mask" "F.Paste")
			(net "P3V3_AUX")
		)
		(pad "2" smd circle
			(at 0.40005 0 180)
			(size 0 0)
			(layers "F.Cu" "F.Mask" "F.Paste")
			(net "JTAG_RST_DBP_RST_CO_N")
		)
	)
	(footprint ""
		(layer "F.Cu")
		(at 96.797876 -79.078836)
		(property "Reference" "D95"
			(at -48.49241 38.649402 90)
			(unlocked yes)
			(layer "F.SilkS")
			(effects
				(font
					(size 0.635 0.4064)
					(thickness 0.1524)
				)
				(justify left)
			)
		)
		(property "Value" ""
			(at 0 0 0)
			(layer "F.Fab")
			(effects
				(font
					(size 1.27 1.27)
				)
			)
		)
		(duplicate_pad_numbers_are_jumpers no)
		(fp_line
			(start -0.90678 0.4826)
			(end -0.90678 -0.4699)
			(stroke
				(width 0.1524)
				(type default)
			)
			(layer "F.SilkS")
		)
		(fp_line
			(start -0.89408 -0.4826)
			(end 0.90678 -0.4826)
			(stroke
				(width 0.1524)
				(type default)
			)
			(layer "F.SilkS")
		)
		(fp_line
			(start -0.79248 -0.4826)
			(end 1.03378 -0.4826)
			(stroke
				(width 0.1524)
				(type default)
			)
			(layer "F.SilkS")
		)
		(fp_line
			(start -0.64008 -0.4826)
			(end 1.16078 -0.4826)
			(stroke
				(width 0.1524)
				(type default)
			)
			(layer "F.SilkS")
		)
		(fp_line
			(start 0.90678 -0.4826)
			(end 0.90678 0.4826)
			(stroke
				(width 0.1524)
				(type default)
			)
			(layer "F.SilkS")
		)
		(fp_line
			(start 0.90678 0.4826)
			(end -0.90678 0.4826)
			(stroke
				(width 0.1524)
				(type default)
			)
			(layer "F.SilkS")
		)
		(fp_line
			(start 1.03378 -0.4826)
			(end 1.03378 0.4826)
			(stroke
				(width 0.1524)
				(type default)
			)
			(layer "F.SilkS")
		)
		(fp_line
			(start 1.03378 0.4826)
			(end -0.79248 0.4826)
			(stroke
				(width 0.1524)
				(type default)
			)
			(layer "F.SilkS")
		)
		(fp_line
			(start 1.16078 -0.4826)
			(end 1.16078 0.4826)
			(stroke
				(width 0.1524)
				(type default)
			)
			(layer "F.SilkS")
		)
		(fp_line
			(start 1.16078 0.4826)
			(end -0.64008 0.4826)
			(stroke
				(width 0.1524)
				(type default)
			)
			(layer "F.SilkS")
		)
		(fp_line
			(start -0.499872 -0.249936)
			(end 0.499872 -0.249936)
			(stroke
				(width 0.1)
				(type default)
			)
			(layer "F.Fab")
		)
		(fp_line
			(start -0.499872 0.249936)
			(end -0.499872 -0.249936)
			(stroke
				(width 0.1)
				(type default)
			)
			(layer "F.Fab")
		)
		(fp_line
			(start 0.499872 -0.249936)
			(end 0.499872 0.249936)
			(stroke
				(width 0.1)
				(type default)
			)
			(layer "F.Fab")
		)
		(fp_line
			(start 0.499872 0.249936)
			(end -0.499872 0.249936)
			(stroke
				(width 0.1)
				(type default)
			)
			(layer "F.Fab")
		)
		(pad "A" smd rect
			(at -0.47498 0)
			(size 0.6096 0.7112)
			(layers "F.Cu" "F.Mask" "F.Paste")
			(net "LED_FM_PCH_SLP_S3_N")
		)
		(pad "C" smd rect
			(at 0.47498 0)
			(size 0.6096 0.7112)
			(layers "F.Cu" "F.Mask" "F.Paste")
			(net "LED_FM_PCH_SLP_S3_N_D")
		)
	)
)
